# T6G (Grand Teton) — schematic netlist excerpt (pin names and nets, part order shuffled) for the footprints in the layout excerpt that follows; sources: Cadence DE-HDL packaged netlist, KiCad conversion of 04192023_DAF0TMB3IC0_F0TG_MB_C_brd_V02_OCP.brd

C2259  Q_CAP  22UF 4V 20% X6S  pkg C0402  page 72 : A = PVDDCR_SOC_P1 ; B = GND
C2489  Q_CAP  22UF 4V 20% X6S  pkg C0402  page 74 : A = PVDD11_S3_P1 ; B = GND

(kicad_pcb
	(version 20260206)
	(generator "pcbnew")
	(generator_version "10.0")
	(general
		(thickness 1.6)
		(legacy_teardrops no)
	)
	(paper "A4")
	(title_block
		(title "04192023_DAF0TMB3IC0_F0TG_MB_C_brd_V02_OCP.brd")
		(comment 1 "Grand Teton / footprints 5850-5851 of 8354")
	)
	(layers
		(0 "F.Cu" signal "TOP")
		(4 "In1.Cu" signal "GND")
		(6 "In2.Cu" signal "IN1")
		(8 "In3.Cu" signal "GND1")
		(10 "In4.Cu" signal "IN2")
		(12 "In5.Cu" signal "GND2")
		(14 "In6.Cu" signal "IN3")
		(16 "In7.Cu" signal "GND3")
		(18 "In8.Cu" signal "VCC")
		(20 "In9.Cu" signal "VCC1")
		(22 "In10.Cu" signal "GND4")
		(24 "In11.Cu" signal "IN4")
		(26 "In12.Cu" signal "GND5")
		(28 "In13.Cu" signal "IN5")
		(30 "In14.Cu" signal "GND6")
		(32 "In15.Cu" signal "IN6")
		(34 "In16.Cu" signal "GND7")
		(2 "B.Cu" signal "BOTTOM")
		(9 "F.Adhes" user "F.Adhesive")
		(11 "B.Adhes" user "B.Adhesive")
		(13 "F.Paste" user "Package Geometry/Pastemask Top")
		(15 "B.Paste" user "Package Geometry/Pastemask Bottom")
		(5 "F.SilkS" user "Ref Des/Silkscreen Top")
		(7 "B.SilkS" user "Ref Des/Silkscreen Bottom")
		(1 "F.Mask" user "Board Geometry/Soldermask Top")
		(3 "B.Mask" user "Board Geometry/Soldermask Bottom")
		(17 "Dwgs.User" user "User.Drawings")
		(19 "Cmts.User" user "User.Comments")
		(21 "Eco1.User" user "User.Eco1")
		(23 "Eco2.User" user "User.Eco2")
		(25 "Edge.Cuts" user "Board Geometry/Outline")
		(27 "Margin" user)
		(31 "F.CrtYd" user "Package Geometry/Place Bound Top")
		(29 "B.CrtYd" user "Package Geometry/Place Bound Bottom")
		(35 "F.Fab" user "Ref Des/Assembly Top")
		(33 "B.Fab" user "Ref Des/Assembly Bottom")
	)
	(footprint ""
		(layer "B.Cu")
		(at 119.293386 -251.781564)
		(property "Reference" "C2259"
			(at 0 0 0)
			(layer "B.SilkS")
			(hide yes)
			(effects
				(font
					(size 1.27 1.27)
				)
				(justify mirror)
			)
		)
		(property "Value" ""
			(at 0 0 0)
			(layer "B.Fab")
			(effects
				(font
					(size 1.27 1.27)
				)
				(justify mirror)
			)
		)
		(duplicate_pad_numbers_are_jumpers no)
		(fp_line
			(start -0.7874 -0.4064)
			(end -0.7874 0.4064)
			(stroke
				(width 0.1524)
				(type default)
			)
			(layer "B.SilkS")
		)
		(fp_line
			(start -0.7874 0.4064)
			(end 0.7874 0.4064)
			(stroke
				(width 0.1524)
				(type default)
			)
			(layer "B.SilkS")
		)
		(fp_line
			(start 0.7874 -0.4064)
			(end -0.7874 -0.4064)
			(stroke
				(width 0.1524)
				(type default)
			)
			(layer "B.SilkS")
		)
		(fp_line
			(start 0.7874 0.4064)
			(end 0.7874 -0.4064)
			(stroke
				(width 0.1524)
				(type default)
			)
			(layer "B.SilkS")
		)
		(fp_line
			(start -0.67945 -0.3048)
			(end -0.67945 0.3048)
			(stroke
				(width 0.1)
				(type default)
			)
			(layer "B.Fab")
		)
		(fp_line
			(start -0.67945 0.3048)
			(end -0.120396 0.3048)
			(stroke
				(width 0.1)
				(type default)
			)
			(layer "B.Fab")
		)
		(fp_line
			(start -0.12065 -0.3048)
			(end -0.67945 -0.3048)
			(stroke
				(width 0.1)
				(type default)
			)
			(layer "B.Fab")
		)
		(fp_line
			(start -0.12065 -0.2794)
			(end -0.12065 -0.3048)
			(stroke
				(width 0.1)
				(type default)
			)
			(layer "B.Fab")
		)
		(fp_line
			(start -0.120396 0.2794)
			(end 0.12065 0.2794)
			(stroke
				(width 0.1)
				(type default)
			)
			(layer "B.Fab")
		)
		(fp_line
			(start -0.120396 0.3048)
			(end -0.120396 0.2794)
			(stroke
				(width 0.1)
				(type default)
			)
			(layer "B.Fab")
		)
		(fp_line
			(start 0.12065 -0.305054)
			(end 0.12065 -0.2794)
			(stroke
				(width 0.1)
				(type default)
			)
			(layer "B.Fab")
		)
		(fp_line
			(start 0.12065 -0.2794)
			(end -0.12065 -0.2794)
			(stroke
				(width 0.1)
				(type default)
			)
			(layer "B.Fab")
		)
		(fp_line
			(start 0.12065 0.2794)
			(end 0.12065 0.3048)
			(stroke
				(width 0.1)
				(type default)
			)
			(layer "B.Fab")
		)
		(fp_line
			(start 0.12065 0.3048)
			(end 0.67945 0.3048)
			(stroke
				(width 0.1)
				(type default)
			)
			(layer "B.Fab")
		)
		(fp_line
			(start 0.67945 -0.305054)
			(end 0.12065 -0.305054)
			(stroke
				(width 0.1)
				(type default)
			)
			(layer "B.Fab")
		)
		(fp_line
			(start 0.67945 0.3048)
			(end 0.67945 -0.305054)
			(stroke
				(width 0.1)
				(type default)
			)
			(layer "B.Fab")
		)
		(pad "1" smd circle
			(at 0.40005 0 180)
			(size 0 0)
			(layers "B.Cu" "B.Mask" "B.Paste")
			(net "PVDDCR_SOC_P1")
		)
		(pad "2" smd circle
			(at -0.40005 0 180)
			(size 0 0)
			(layers "B.Cu" "B.Mask" "B.Paste")
			(net "GND")
		)
	)
	(footprint ""
		(layer "B.Cu")
		(at 105.960164 -262.205216)
		(property "Reference" "C2489"
			(at 0 0 0)
			(layer "B.SilkS")
			(hide yes)
			(effects
				(font
					(size 1.27 1.27)
				)
				(justify mirror)
			)
		)
		(property "Value" ""
			(at 0 0 0)
			(layer "B.Fab")
			(effects
				(font
					(size 1.27 1.27)
				)
				(justify mirror)
			)
		)
		(duplicate_pad_numbers_are_jumpers no)
		(fp_line
			(start -0.7874 -0.4064)
			(end -0.7874 0.4064)
			(stroke
				(width 0.1524)
				(type default)
			)
			(layer "B.SilkS")
		)
		(fp_line
			(start -0.7874 0.4064)
			(end 0.7874 0.4064)
			(stroke
				(width 0.1524)
				(type default)
			)
			(layer "B.SilkS")
		)
		(fp_line
			(start 0.7874 -0.4064)
			(end -0.7874 -0.4064)
			(stroke
				(width 0.1524)
				(type default)
			)
			(layer "B.SilkS")
		)
		(fp_line
			(start 0.7874 0.4064)
			(end 0.7874 -0.4064)
			(stroke
				(width 0.1524)
				(type default)
			)
			(layer "B.SilkS")
		)
		(fp_line
			(start -0.67945 -0.3048)
			(end -0.67945 0.3048)
			(stroke
				(width 0.1)
				(type default)
			)
			(layer "B.Fab")
		)
		(fp_line
			(start -0.67945 0.3048)
			(end -0.120396 0.3048)
			(stroke
				(width 0.1)
				(type default)
			)
			(layer "B.Fab")
		)
		(fp_line
			(start -0.12065 -0.3048)
			(end -0.67945 -0.3048)
			(stroke
				(width 0.1)
				(type default)
			)
			(layer "B.Fab")
		)
		(fp_line
			(start -0.12065 -0.2794)
			(end -0.12065 -0.3048)
			(stroke
				(width 0.1)
				(type default)
			)
			(layer "B.Fab")
		)
		(fp_line
			(start -0.120396 0.2794)
			(end 0.12065 0.2794)
			(stroke
				(width 0.1)
				(type default)
			)
			(layer "B.Fab")
		)
		(fp_line
			(start -0.120396 0.3048)
			(end -0.120396 0.2794)
			(stroke
				(width 0.1)
				(type default)
			)
			(layer "B.Fab")
		)
		(fp_line
			(start 0.12065 -0.305054)
			(end 0.12065 -0.2794)
			(stroke
				(width 0.1)
				(type default)
			)
			(layer "B.Fab")
		)
		(fp_line
			(start 0.12065 -0.2794)
			(end -0.12065 -0.2794)
			(stroke
				(width 0.1)
				(type default)
			)
			(layer "B.Fab")
		)
		(fp_line
			(start 0.12065 0.2794)
			(end 0.12065 0.3048)
			(stroke
				(width 0.1)
				(type default)
			)
			(layer "B.Fab")
		)
		(fp_line
			(start 0.12065 0.3048)
			(end 0.67945 0.3048)
			(stroke
				(width 0.1)
				(type default)
			)
			(layer "B.Fab")
		)
		(fp_line
			(start 0.67945 -0.305054)
			(end 0.12065 -0.305054)
			(stroke
				(width 0.1)
				(type default)
			)
			(layer "B.Fab")
		)
		(fp_line
			(start 0.67945 0.3048)
			(end 0.67945 -0.305054)
			(stroke
				(width 0.1)
				(type default)
			)
			(layer "B.Fab")
		)
		(pad "1" smd circle
			(at 0.40005 0 180)
			(size 0 0)
			(layers "B.Cu" "B.Mask" "B.Paste")
			(net "PVDD11_S3_P1")
		)
		(pad "2" smd circle
			(at -0.40005 0 180)
			(size 0 0)
			(layers "B.Cu" "B.Mask" "B.Paste")
			(net "GND")
		)
	)
)
